(kicad_pcb
	(version 20241229)
	(generator "pcbnew")
	(generator_version "9.0")
	(general
		(thickness 1.6)
		(legacy_teardrops no)
	)
	(paper "A4")
	(title_block
		(title "GMSL Deserializer")
		(date "2025-10-09")
		(rev "1.0.4")
		(company "Antmicro Ltd")
		(comment 1 "www.antmicro.com")
		(comment 9 "footprints 228-233 of 235")
	)
	(layers
		(0 "F.Cu" signal)
		(4 "In1.Cu" power)
		(6 "In2.Cu" power)
		(2 "B.Cu" signal)
		(9 "F.Adhes" user "F.Adhesive")
		(11 "B.Adhes" user "B.Adhesive")
		(13 "F.Paste" user)
		(15 "B.Paste" user)
		(5 "F.SilkS" user "F.Silkscreen")
		(7 "B.SilkS" user "B.Silkscreen")
		(1 "F.Mask" user)
		(3 "B.Mask" user)
		(17 "Dwgs.User" user "User.Drawings")
		(19 "Cmts.User" user "User.Comments")
		(21 "Eco1.User" user "User.Eco1")
		(23 "Eco2.User" user "User.Eco2")
		(25 "Edge.Cuts" user)
		(27 "Margin" user)
		(31 "F.CrtYd" user "F.Courtyard")
		(29 "B.CrtYd" user "B.Courtyard")
		(35 "F.Fab" user)
		(33 "B.Fab" user)
	)
	(footprint "antmicro-footprints:C_0402_1005Metric"
		(layer "B.Cu")
		(at 139.954 80.01 -45)
		(descr "Capacitor SMD 0402")
		(tags "capacitor SMD 0402")
		(property "Reference" "C52"
			(at -1.612512 0.317093 315)
			(unlocked yes)
			(layer "B.SilkS")
			(effects
				(font
					(size 0.7 0.7)
					(thickness 0.15)
				)
				(justify left bottom mirror)
			)
		)
		(property "Value" "C_100n_0402"
			(at -1.022927 -2.155213 135)
			(layer "B.Fab")
			(effects
				(font
					(size 0.7 0.7)
					(thickness 0.15)
				)
				(justify left bottom mirror)
			)
		)
		(property "Datasheet" "https://www.murata.com/products/productdetail?partno=GRM155R61H104KE14%23"
			(at 0 0 315)
			(layer "F.Fab")
			(hide yes)
			(effects
				(font
					(size 1.27 1.27)
					(thickness 0.15)
				)
			)
		)
		(property "Description" "SMD Multilayer Ceramic Capacitor, 0.1 µF, 50 V, 0402 [1005 Metric], ± 10%, X5R, GRM Series"
			(at 0 0 315)
			(layer "F.Fab")
			(hide yes)
			(effects
				(font
					(size 1.27 1.27)
					(thickness 0.15)
				)
			)
		)
		(property "Author" "Antmicro"
			(at -15.584036 122.396809 0)
			(layer "B.Fab")
			(hide yes)
			(effects
				(font
					(size 1 1)
					(thickness 0.15)
				)
				(justify mirror)
			)
		)
		(property "Dielectric" "X5R"
			(at -15.584036 122.396809 0)
			(layer "B.Fab")
			(hide yes)
			(effects
				(font
					(size 1 1)
					(thickness 0.15)
				)
				(justify mirror)
			)
		)
		(property "License" "Apache-2.0"
			(at -15.584036 122.396809 0)
			(layer "B.Fab")
			(hide yes)
			(effects
				(font
					(size 1 1)
					(thickness 0.15)
				)
				(justify mirror)
			)
		)
		(property "MPN" "GRM155R61H104KE14D"
			(at -15.584036 122.396809 0)
			(layer "B.Fab")
			(hide yes)
			(effects
				(font
					(size 1 1)
					(thickness 0.15)
				)
				(justify mirror)
			)
		)
		(property "Manufacturer" "Murata"
			(at -15.584036 122.396809 0)
			(layer "B.Fab")
			(hide yes)
			(effects
				(font
					(size 1 1)
					(thickness 0.15)
				)
				(justify mirror)
			)
		)
		(property "Val" "100n"
			(at -15.584036 122.396809 0)
			(layer "B.Fab")
			(hide yes)
			(effects
				(font
					(size 1 1)
					(thickness 0.15)
				)
				(justify mirror)
			)
		)
		(property "Voltage" "50V"
			(at -15.584036 122.396809 0)
			(layer "B.Fab")
			(hide yes)
			(effects
				(font
					(size 1 1)
					(thickness 0.15)
				)
				(justify mirror)
			)
		)
		(sheetname "/Deserializer/")
		(sheetfile "deserializer.kicad_sch")
		(attr smd)
		(fp_poly
			(pts
				(xy -0.925 0.47) (xy 0.925 0.47) (xy 0.925 -0.47) (xy -0.925 -0.47)
			)
			(stroke
				(width 0.05)
				(type default)
			)
			(fill no)
			(layer "B.CrtYd")
		)
		(fp_line
			(start -0.494 0.25)
			(end -0.494 -0.248)
			(stroke
				(width 0.15)
				(type solid)
			)
			(layer "B.Fab")
		)
		(fp_line
			(start -0.494 -0.248)
			(end 0.504 -0.248)
			(stroke
				(width 0.15)
				(type solid)
			)
			(layer "B.Fab")
		)
		(fp_line
			(start 0.504 0.25)
			(end -0.494 0.25)
			(stroke
				(width 0.15)
				(type solid)
			)
			(layer "B.Fab")
		)
		(fp_line
			(start 0.504 -0.248)
			(end 0.504 0.25)
			(stroke
				(width 0.15)
				(type solid)
			)
			(layer "B.Fab")
		)
		(pad "1" smd roundrect
			(at -0.48 0 315)
			(size 0.59 0.64)
			(layers "B.Cu" "B.Mask" "B.Paste")
			(roundrect_rratio 0.25)
			(net 1 "GND")
			(pintype "passive")
		)
		(pad "2" smd roundrect
			(at 0.48 0 315)
			(size 0.59 0.64)
			(layers "B.Cu" "B.Mask" "B.Paste")
			(roundrect_rratio 0.25)
			(net 146 "VDDIO")
			(pintype "passive")
		)
	)
	(footprint "antmicro-footprints:TP_SMD_0.75mm"
		(layer "B.Cu")
		(at 155.448 97.89 180)
		(property "Reference" "TP23"
			(at 0 0.6 0)
			(layer "B.SilkS")
			(hide yes)
			(effects
				(font
					(size 0.7 0.7)
					(thickness 0.15)
				)
				(justify left bottom mirror)
			)
		)
		(property "Value" "TP_0.75mm_SMD"
			(at 0 -1.2 0)
			(layer "B.Fab")
			(effects
				(font
					(size 0.7 0.7)
					(thickness 0.15)
				)
				(justify left bottom mirror)
			)
		)
		(property "Description" "SMT test point"
			(at 0 0 0)
			(layer "B.Fab")
			(hide yes)
			(effects
				(font
					(size 1.27 1.27)
					(thickness 0.15)
				)
				(justify mirror)
			)
		)
		(property "MPN" ""
			(at 0 0 0)
			(unlocked yes)
			(layer "B.Fab")
			(hide yes)
			(effects
				(font
					(size 1 1)
					(thickness 0.15)
				)
				(justify mirror)
			)
		)
		(property "Manufacturer" ""
			(at 0 0 0)
			(unlocked yes)
			(layer "B.Fab")
			(hide yes)
			(effects
				(font
					(size 1 1)
					(thickness 0.15)
				)
				(justify mirror)
			)
		)
		(property "Author" "Antmicro"
			(at 0 0 0)
			(unlocked yes)
			(layer "B.Fab")
			(hide yes)
			(effects
				(font
					(size 1 1)
					(thickness 0.15)
				)
				(justify mirror)
			)
		)
		(property "License" "Apache-2.0"
			(at 0 0 0)
			(unlocked yes)
			(layer "B.Fab")
			(hide yes)
			(effects
				(font
					(size 1 1)
					(thickness 0.15)
				)
				(justify mirror)
			)
		)
		(sheetname "/Connectors/")
		(sheetfile "connectors.kicad_sch")
		(attr exclude_from_pos_files)
		(fp_circle
			(center 0 0)
			(end 0.475 0)
			(stroke
				(width 0.05)
				(type default)
			)
			(fill no)
			(layer "B.CrtYd")
		)
		(fp_text user "Author: Antmicro"
			(at -0.4 -3.901 0)
			(layer "B.Fab")
			(effects
				(font
					(size 0.7 0.7)
					(thickness 0.15)
				)
				(justify left bottom mirror)
			)
		)
		(fp_text user "License: Apache-2.0"
			(at -0.4 -5.101 0)
			(layer "B.Fab")
			(effects
				(font
					(size 0.7 0.7)
					(thickness 0.15)
				)
				(justify left bottom mirror)
			)
		)
		(fp_text user "${REFERENCE}"
			(at -0.4 -2.7 0)
			(layer "B.Fab")
			(effects
				(font
					(size 0.7 0.7)
					(thickness 0.15)
				)
				(justify left bottom mirror)
			)
		)
		(pad "1" smd circle
			(at 0 0 180)
			(size 0.75 0.75)
			(layers "B.Cu" "B.Mask")
			(net 113 "/Connectors/FFC_5V")
			(pinfunction "1")
			(pintype "passive")
		)
	)
	(footprint "antmicro-footprints:TP_SMD_0.75mm"
		(layer "B.Cu")
		(at 150.876 97.89 180)
		(property "Reference" "TP19"
			(at 0 0.6 0)
			(layer "B.SilkS")
			(hide yes)
			(effects
				(font
					(size 0.7 0.7)
					(thickness 0.15)
				)
				(justify left bottom mirror)
			)
		)
		(property "Value" "TP_0.75mm_SMD"
			(at 0 -1.2 0)
			(layer "B.Fab")
			(effects
				(font
					(size 0.7 0.7)
					(thickness 0.15)
				)
				(justify left bottom mirror)
			)
		)
		(property "Description" "SMT test point"
			(at 0 0 0)
			(layer "B.Fab")
			(hide yes)
			(effects
				(font
					(size 1.27 1.27)
					(thickness 0.15)
				)
				(justify mirror)
			)
		)
		(property "MPN" ""
			(at 0 0 0)
			(unlocked yes)
			(layer "B.Fab")
			(hide yes)
			(effects
				(font
					(size 1 1)
					(thickness 0.15)
				)
				(justify mirror)
			)
		)
		(property "Manufacturer" ""
			(at 0 0 0)
			(unlocked yes)
			(layer "B.Fab")
			(hide yes)
			(effects
				(font
					(size 1 1)
					(thickness 0.15)
				)
				(justify mirror)
			)
		)
		(property "Author" "Antmicro"
			(at 0 0 0)
			(unlocked yes)
			(layer "B.Fab")
			(hide yes)
			(effects
				(font
					(size 1 1)
					(thickness 0.15)
				)
				(justify mirror)
			)
		)
		(property "License" "Apache-2.0"
			(at 0 0 0)
			(unlocked yes)
			(layer "B.Fab")
			(hide yes)
			(effects
				(font
					(size 1 1)
					(thickness 0.15)
				)
				(justify mirror)
			)
		)
		(sheetname "/Power/")
		(sheetfile "power.kicad_sch")
		(attr exclude_from_pos_files)
		(fp_circle
			(center 0 0)
			(end 0.475 0)
			(stroke
				(width 0.05)
				(type default)
			)
			(fill no)
			(layer "B.CrtYd")
		)
		(fp_text user "Author: Antmicro"
			(at -0.4 -3.901 0)
			(layer "B.Fab")
			(effects
				(font
					(size 0.7 0.7)
					(thickness 0.15)
				)
				(justify left bottom mirror)
			)
		)
		(fp_text user "${REFERENCE}"
			(at -0.4 -2.7 0)
			(layer "B.Fab")
			(effects
				(font
					(size 0.7 0.7)
					(thickness 0.15)
				)
				(justify left bottom mirror)
			)
		)
		(fp_text user "License: Apache-2.0"
			(at -0.4 -5.101 0)
			(layer "B.Fab")
			(effects
				(font
					(size 0.7 0.7)
					(thickness 0.15)
				)
				(justify left bottom mirror)
			)
		)
		(pad "1" smd circle
			(at 0 0 180)
			(size 0.75 0.75)
			(layers "B.Cu" "B.Mask")
			(net 5 "+5V")
			(pinfunction "1")
			(pintype "passive")
		)
	)
	(footprint "antmicro-footprints:R_0402_1005Metric"
		(layer "B.Cu")
		(at 155.467792 96.395897 90)
		(descr "Resistor SMD 0402")
		(tags "resistor SMD 0402")
		(property "Reference" "R71"
			(at 5.73053 0.434221 90)
			(layer "B.SilkS")
			(effects
				(font
					(size 0.7 0.7)
					(thickness 0.15)
				)
				(justify right bottom mirror)
			)
		)
		(property "Value" "R_470R_0402"
			(at -1.011843 -1.772046 90)
			(layer "B.Fab")
			(effects
				(font
					(size 0.7 0.7)
					(thickness 0.15)
				)
				(justify right bottom mirror)
			)
		)
		(property "Datasheet" "https://www.bourns.com/docs/product-datasheets/cr.pdf"
			(at 0 0 90)
			(layer "F.Fab")
			(hide yes)
			(effects
				(font
					(size 1.27 1.27)
					(thickness 0.15)
				)
			)
		)
		(property "Description" "SMD Chip Resistor, 470 ohm, ± 1%, 62.5 mW, 0402 [1005 Metric], Thick Film, General Purpose"
			(at 0 0 90)
			(layer "F.Fab")
			(hide yes)
			(effects
				(font
					(size 1.27 1.27)
					(thickness 0.15)
				)
			)
		)
		(property "Author" "Antmicro"
			(at 333.650804 53.296134 135)
			(layer "B.Fab")
			(hide yes)
			(effects
				(font
					(size 1 1)
					(thickness 0.15)
				)
				(justify mirror)
			)
		)
		(property "License" "Apache-2.0"
			(at 333.650804 53.296134 135)
			(layer "B.Fab")
			(hide yes)
			(effects
				(font
					(size 1 1)
					(thickness 0.15)
				)
				(justify mirror)
			)
		)
		(property "MPN" "CR0402-FX-4700GLF"
			(at 333.650804 53.296134 135)
			(layer "B.Fab")
			(hide yes)
			(effects
				(font
					(size 1 1)
					(thickness 0.15)
				)
				(justify mirror)
			)
		)
		(property "Manufacturer" "Bourns"
			(at 333.650804 53.296134 135)
			(layer "B.Fab")
			(hide yes)
			(effects
				(font
					(size 1 1)
					(thickness 0.15)
				)
				(justify mirror)
			)
		)
		(property "Tolerance" "1%"
			(at 333.650804 53.296134 135)
			(layer "B.Fab")
			(hide yes)
			(effects
				(font
					(size 1 1)
					(thickness 0.15)
				)
				(justify mirror)
			)
		)
		(property "Val" "470R"
			(at 333.650804 53.296134 135)
			(layer "B.Fab")
			(hide yes)
			(effects
				(font
					(size 1 1)
					(thickness 0.15)
				)
				(justify mirror)
			)
		)
		(sheetname "/Connectors/")
		(sheetfile "connectors.kicad_sch")
		(attr smd)
		(fp_poly
			(pts
				(xy -0.925 0.47) (xy 0.925 0.47) (xy 0.925 -0.47) (xy -0.925 -0.47)
			)
			(stroke
				(width 0.05)
				(type default)
			)
			(fill no)
			(layer "B.CrtYd")
		)
		(fp_poly
			(pts
				(xy -0.5 0.25) (xy 0.5 0.25) (xy 0.5 -0.25) (xy -0.5 -0.25)
			)
			(stroke
				(width 0.15)
				(type solid)
			)
			(fill no)
			(layer "B.Fab")
		)
		(pad "1" smd roundrect
			(at -0.48 0 90)
			(size 0.59 0.64)
			(layers "B.Cu" "B.Mask" "B.Paste")
			(roundrect_rratio 0.25)
			(net 1 "GND")
			(pintype "passive")
		)
		(pad "2" smd roundrect
			(at 0.48 0 90)
			(size 0.59 0.64)
			(layers "B.Cu" "B.Mask" "B.Paste")
			(roundrect_rratio 0.25)
			(net 109 "Net-(D13-C)")
			(pintype "passive")
		)
	)
	(footprint "antmicro-footprints:C_0402_1005Metric"
		(layer "B.Cu")
		(at 140.716 79.248 -45)
		(descr "Capacitor SMD 0402")
		(tags "capacitor SMD 0402")
		(property "Reference" "C54"
			(at -1.588513 0.317094 315)
			(unlocked yes)
			(layer "B.SilkS")
			(effects
				(font
					(size 0.7 0.7)
					(thickness 0.15)
				)
				(justify left bottom mirror)
			)
		)
		(property "Value" "C_10u_0402"
			(at -1.022927 -2.155213 135)
			(layer "B.Fab")
			(effects
				(font
					(size 0.7 0.7)
					(thickness 0.15)
				)
				(justify left bottom mirror)
			)
		)
		(property "Datasheet" "https://www.yageo.com/en/Chart/Download/pdf/CC0402MRX5R5BB106"
			(at 0 0 315)
			(layer "F.Fab")
			(hide yes)
			(effects
				(font
					(size 1.27 1.27)
					(thickness 0.15)
				)
			)
		)
		(property "Description" "SMD Multilayer Ceramic Capacitor, 10 µF, 6.3 V, 0402 [1005 Metric], ± 20%, X5R, CC Series"
			(at 0 0 315)
			(layer "F.Fab")
			(hide yes)
			(effects
				(font
					(size 1.27 1.27)
					(thickness 0.15)
				)
			)
		)
		(property "Author" "Antmicro"
			(at -14.822036 122.712439 0)
			(layer "B.Fab")
			(hide yes)
			(effects
				(font
					(size 1 1)
					(thickness 0.15)
				)
				(justify mirror)
			)
		)
		(property "Dielectric" ""
			(at -14.822036 122.712439 0)
			(layer "B.Fab")
			(hide yes)
			(effects
				(font
					(size 1 1)
					(thickness 0.15)
				)
				(justify mirror)
			)
		)
		(property "License" "Apache-2.0"
			(at -14.822036 122.712439 0)
			(layer "B.Fab")
			(hide yes)
			(effects
				(font
					(size 1 1)
					(thickness 0.15)
				)
				(justify mirror)
			)
		)
		(property "MPN" "CC0402MRX5R5BB106"
			(at -14.822036 122.712439 0)
			(layer "B.Fab")
			(hide yes)
			(effects
				(font
					(size 1 1)
					(thickness 0.15)
				)
				(justify mirror)
			)
		)
		(property "Manufacturer" "YAGEO"
			(at -14.822036 122.712439 0)
			(layer "B.Fab")
			(hide yes)
			(effects
				(font
					(size 1 1)
					(thickness 0.15)
				)
				(justify mirror)
			)
		)
		(property "Val" "10u"
			(at -14.822036 122.712439 0)
			(layer "B.Fab")
			(hide yes)
			(effects
				(font
					(size 1 1)
					(thickness 0.15)
				)
				(justify mirror)
			)
		)
		(property "Voltage" ""
			(at -14.822036 122.712439 0)
			(layer "B.Fab")
			(hide yes)
			(effects
				(font
					(size 1 1)
					(thickness 0.15)
				)
				(justify mirror)
			)
		)
		(sheetname "/Deserializer/")
		(sheetfile "deserializer.kicad_sch")
		(attr smd)
		(fp_poly
			(pts
				(xy -0.925 0.47) (xy 0.925 0.47) (xy 0.925 -0.47) (xy -0.925 -0.47)
			)
			(stroke
				(width 0.05)
				(type default)
			)
			(fill no)
			(layer "B.CrtYd")
		)
		(fp_line
			(start -0.494 0.25)
			(end -0.494 -0.248)
			(stroke
				(width 0.15)
				(type solid)
			)
			(layer "B.Fab")
		)
		(fp_line
			(start -0.494 -0.248)
			(end 0.504 -0.248)
			(stroke
				(width 0.15)
				(type solid)
			)
			(layer "B.Fab")
		)
		(fp_line
			(start 0.504 0.25)
			(end -0.494 0.25)
			(stroke
				(width 0.15)
				(type solid)
			)
			(layer "B.Fab")
		)
		(fp_line
			(start 0.504 -0.248)
			(end 0.504 0.25)
			(stroke
				(width 0.15)
				(type solid)
			)
			(layer "B.Fab")
		)
		(pad "1" smd roundrect
			(at -0.48 0 315)
			(size 0.59 0.64)
			(layers "B.Cu" "B.Mask" "B.Paste")
			(roundrect_rratio 0.25)
			(net 1 "GND")
			(pintype "passive")
		)
		(pad "2" smd roundrect
			(at 0.48 0 315)
			(size 0.59 0.64)
			(layers "B.Cu" "B.Mask" "B.Paste")
			(roundrect_rratio 0.25)
			(net 146 "VDDIO")
			(pintype "passive")
		)
	)
	(footprint "antmicro-footprints:TP_SMD_0.75mm"
		(layer "B.Cu")
		(at 155.7 76.75 180)
		(property "Reference" "TP24"
			(at 0 0.6 0)
			(layer "B.SilkS")
			(hide yes)
			(effects
				(font
					(size 0.7 0.7)
					(thickness 0.15)
				)
				(justify left bottom mirror)
			)
		)
		(property "Value" "TP_0.75mm_SMD"
			(at 0 -1.2 0)
			(layer "B.Fab")
			(effects
				(font
					(size 0.7 0.7)
					(thickness 0.15)
				)
				(justify left bottom mirror)
			)
		)
		(property "Description" "SMT test point"
			(at 0 0 0)
			(layer "B.Fab")
			(hide yes)
			(effects
				(font
					(size 1.27 1.27)
					(thickness 0.15)
				)
				(justify mirror)
			)
		)
		(property "MPN" ""
			(at 0 0 0)
			(unlocked yes)
			(layer "B.Fab")
			(hide yes)
			(effects
				(font
					(size 1 1)
					(thickness 0.15)
				)
				(justify mirror)
			)
		)
		(property "Manufacturer" ""
			(at 0 0 0)
			(unlocked yes)
			(layer "B.Fab")
			(hide yes)
			(effects
				(font
					(size 1 1)
					(thickness 0.15)
				)
				(justify mirror)
			)
		)
		(property "Author" "Antmicro"
			(at 0 0 0)
			(unlocked yes)
			(layer "B.Fab")
			(hide yes)
			(effects
				(font
					(size 1 1)
					(thickness 0.15)
				)
				(justify mirror)
			)
		)
		(property "License" "Apache-2.0"
			(at 0 0 0)
			(unlocked yes)
			(layer "B.Fab")
			(hide yes)
			(effects
				(font
					(size 1 1)
					(thickness 0.15)
				)
				(justify mirror)
			)
		)
		(sheetname "/Connectors/")
		(sheetfile "connectors.kicad_sch")
		(attr exclude_from_pos_files)
		(fp_circle
			(center 0 0)
			(end 0.475 0)
			(stroke
				(width 0.05)
				(type default)
			)
			(fill no)
			(layer "B.CrtYd")
		)
		(fp_text user "License: Apache-2.0"
			(at -0.4 -5.101 0)
			(layer "B.Fab")
			(effects
				(font
					(size 0.7 0.7)
					(thickness 0.15)
				)
				(justify left bottom mirror)
			)
		)
		(fp_text user "${REFERENCE}"
			(at -0.4 -2.7 0)
			(layer "B.Fab")
			(effects
				(font
					(size 0.7 0.7)
					(thickness 0.15)
				)
				(justify left bottom mirror)
			)
		)
		(fp_text user "Author: Antmicro"
			(at -0.4 -3.901 0)
			(layer "B.Fab")
			(effects
				(font
					(size 0.7 0.7)
					(thickness 0.15)
				)
				(justify left bottom mirror)
			)
		)
		(pad "1" smd circle
			(at 0 0 180)
			(size 0.75 0.75)
			(layers "B.Cu" "B.Mask")
			(net 88 "/Connectors/SDA")
			(pinfunction "1")
			(pintype "passive")
		)
	)
)
